# BASEBOARD_FAB2 (Tioga Pass) — schematic netlist excerpt (pin names and nets, part order shuffled) for the footprints in the layout excerpt that follows; sources: Cadence DE-HDL packaged netlist, KiCad conversion of Wiwynn_Tioga_Pass_MB.brd

J1C1  DM-FCI-CONN76-8R-GP-U-01  pkg CONN-G4  page 182
  PCIE_RX_DP0  = P3E_CPU1_PE3_MP_RXN<8>
  GND1  = GND
  PCIE_RX_DP6  = P3E_CPU1_PE3_MP_RXP<14>
  FAN_TACH3  = GND
  MNG_TX_DP  = TP_IOA5
  \pmbus_alert#\  = GND
  PCIE_TX_DP3  = P3E_CPU1_PE3_MP_C_TXN<11>
  GND2  = GND
  PCIE_RX_DN0  = P3E_CPU1_PE3_MP_RXP<8>
  PCIE_RX_DP3  = P3E_CPU1_PE3_MP_RXN<11>
  PCIE_RX_DN6  = P3E_CPU1_PE3_MP_RXN<14>
  FAN_TACH2  = TP_FM_WAKE_N
  MNG_TX_DN  = IRQ_BOARD_BMC_ALERT_N
  PMBUS_DATA  = SMB_PEHPCPU1_STBY_LVC3_SDA
  PCIE_TX_DN3  = P3E_CPU1_PE3_MP_C_TXP<11>
  PCIE_TX_DP0  = P3E_CPU1_PE3_MP_C_TXN<8>
  GND3  = GND
  PCIE_RX_DN3  = P3E_CPU1_PE3_MP_RXP<11>
  GND4  = GND
  FAN_TACH1  = FM_BB_BMC_MP_GPIO
  GND5  = GND
  PMBUS_CLK  = SMB_PEHPCPU1_STBY_LVC3_SCL
  GND6  = GND
  PCIE_TX_DN0  = P3E_CPU1_PE3_MP_C_TXP<8>
  PCIE_RX_DP1  = P3E_CPU1_PE3_MP_RXN<9>
  GND7  = GND
  PCIE_RX_DP7  = P3E_CPU1_PE3_MP_RXN<15>
  FAN_TACH0  = GND
  MNG_RX_DP  = SMB_LAN_STBY_LVC3_SDA
  GND8  = GND
  PCIE_TX_DP4  = P3E_CPU1_PE3_MP_C_TXN<12>
  GND9  = GND
  PCIE_RX_DN1  = P3E_CPU1_PE3_MP_RXP<9>
  PCIE_RX_DP4  = P3E_CPU1_PE3_MP_RXN<12>
  PCIE_RX_DN7  = P3E_CPU1_PE3_MP_RXP<15>
  \mated_in#\  = TP_IOE4
  MNG_RX_DN  = SMB_LAN_STBY_LVC3_SCL
  PCIE_TX_DP6  = P3E_CPU1_PE3_MP_C_TXN<14>
  PCIE_TX_DN4  = P3E_CPU1_PE3_MP_C_TXP<12>
  PCIE_TX_DP1  = P3E_CPU1_PE3_MP_C_TXN<9>
  GND10  = GND
  PCIE_RX_DN4  = P3E_CPU1_PE3_MP_RXP<12>
  GND11  = GND
  FAN_PWM0  = TP_IOF4
  MB_SLOT_ID0  = GND
  PCIE_TX_DN6  = P3E_CPU1_PE3_MP_C_TXP<14>
  GND12  = GND
  PCIE_TX_DN1  = P3E_CPU1_PE3_MP_C_TXP<9>
  PCIE_RX_DP2  = P3E_CPU1_PE3_MP_RXP<10>
  GND13  = GND
  COM_TX  = TP_IOG3
  GND14  = GND
  MB_SLOT_ID1  = FM_XRC_PRESENT_N
  GND15  = GND
  PCIE_TX_DP5  = P3E_CPU1_PE3_MP_C_TXN<13>
  GND16  = GND
  PCIE_RX_DN2  = P3E_CPU1_PE3_MP_RXN<10>
  PCIE_RX_DP5  = P3E_CPU1_PE3_MP_RXP<13>
  COM_RX  = TP_IOH3
  PCIE_CLK_100M_DP  = TP_IOH4
  MB_SLOT_ID2  = FM_XRC_READY_N
  PCIE_TX_DP7  = P3E_CPU1_PE3_MP_C_TXN<15>
  PCIE_TX_DN5  = P3E_CPU1_PE3_MP_C_TXP<13>
  PCIE_TX_DP2  = P3E_CPU1_PE3_MP_C_TXP<10>
  GND17  = GND
  PCIE_RX_DN5  = P3E_CPU1_PE3_MP_RXN<13>
  \mb_on#\  = GND
  PCIE_CLK_100M_DN  = TP_IOI4
  \pcie_perst#\  = GND
  PCIE_TX_DN7  = P3E_CPU1_PE3_MP_C_TXP<15>
  GND18  = GND
  PCIE_TX_DN2  = P3E_CPU1_PE3_MP_C_TXN<10>
  J2  = GND
  J4  = GND
  J6  = GND
  J8  = GND

(kicad_pcb
	(version 20260206)
	(generator "pcbnew")
	(generator_version "10.0")
	(general
		(thickness 1.6)
		(legacy_teardrops no)
	)
	(paper "A4")
	(title_block
		(title "Wiwynn_Tioga_Pass_MB.brd")
		(comment 1 "Tioga Pass / footprint 1357 of 4770 (J1C1), pads 59-76 of 76")
	)
	(layers
		(0 "F.Cu" signal "TOP")
		(4 "In1.Cu" signal "L2GND")
		(6 "In2.Cu" signal "L3")
		(8 "In3.Cu" signal "L4GND")
		(10 "In4.Cu" signal "L5")
		(12 "In5.Cu" signal "L6GND")
		(14 "In6.Cu" signal "L7VCC")
		(16 "In7.Cu" signal "L8VCC")
		(18 "In8.Cu" signal "L9GND")
		(20 "In9.Cu" signal "L10")
		(22 "In10.Cu" signal "L11GND")
		(24 "In11.Cu" signal "L12")
		(26 "In12.Cu" signal "L13GND")
		(2 "B.Cu" signal "BOTTOM")
		(9 "F.Adhes" user "F.Adhesive")
		(11 "B.Adhes" user "B.Adhesive")
		(13 "F.Paste" user "Package Geometry/Pastemask Top")
		(15 "B.Paste" user "Package Geometry/Pastemask Bottom")
		(5 "F.SilkS" user "Ref Des/Silkscreen Top")
		(7 "B.SilkS" user "Ref Des/Silkscreen Bottom")
		(1 "F.Mask" user "Board Geometry/Soldermask Top")
		(3 "B.Mask" user "Board Geometry/Soldermask Bottom")
		(17 "Dwgs.User" user "User.Drawings")
		(19 "Cmts.User" user "User.Comments")
		(21 "Eco1.User" user "User.Eco1")
		(23 "Eco2.User" user "User.Eco2")
		(25 "Edge.Cuts" user "Board Geometry/Outline")
		(27 "Margin" user)
		(31 "F.CrtYd" user "Package Geometry/Place Bound Top")
		(29 "B.CrtYd" user "Package Geometry/Place Bound Bottom")
		(35 "F.Fab" user "Ref Des/Assembly Top")
		(33 "B.Fab" user "Ref Des/Assembly Bottom")
	)
	(footprint ""
		(layer "F.Cu")
		(at 2.29997 -97.769934 -90)
		(property "Reference" "J1C1"
			(at 0 0 270)
			(layer "F.SilkS")
			(hide yes)
			(effects
				(font
					(size 1.27 1.27)
				)
			)
		)
		(property "Value" "*"
			(at -20.8026 -3.4036 270)
			(unlocked yes)
			(layer "F.Fab")
			(hide yes)
			(effects
				(font
					(size 1.27 1.016)
					(thickness 0.1524)
				)
			)
		)
		(property "Device Type" "DM-FCI-CONN76-8R-GP-U-01_CONN-A"
			(at -20.8026 -4.9276 270)
			(unlocked yes)
			(layer "F.Fab")
			(hide yes)
			(effects
				(font
					(size 1.27 1.016)
					(thickness 0.1524)
				)
			)
		)
		(duplicate_pad_numbers_are_jumpers no)
		(pad "H3" thru_hole circle
			(at -2.999994 -3.599942 270)
			(size 0.8128 0.8128)
			(drill 0.399796)
			(layers "*.Cu" "*.Mask")
			(remove_unused_layers no)
			(net "TP_IOH3")
			(clearance 0.1524)
			(thermal_gap 0.1524)
		)
		(pad "H4" thru_hole circle
			(at -0.999998 -3.50012 270)
			(size 0.8128 0.8128)
			(drill 0.399796)
			(layers "*.Cu" "*.Mask")
			(remove_unused_layers no)
			(net "TP_IOH4")
			(clearance 0.2921)
			(thermal_gap 0.2921)
		)
		(pad "H5" thru_hole circle
			(at 0.999998 -3.599942 270)
			(size 0.8128 0.8128)
			(drill 0.399796)
			(layers "*.Cu" "*.Mask")
			(remove_unused_layers no)
			(net "FM_XRC_READY_N")
			(clearance 0.1524)
			(thermal_gap 0.1524)
		)
		(pad "H6" thru_hole circle
			(at 2.999994 -3.50012 270)
			(size 0.8128 0.8128)
			(drill 0.399796)
			(layers "*.Cu" "*.Mask")
			(remove_unused_layers no)
			(net "P3E_CPU1_PE3_MP_C_TXN<15>")
			(clearance 0.2921)
			(thermal_gap 0.2921)
		)
		(pad "H7" thru_hole circle
			(at 4.99999 -3.599942 270)
			(size 0.8128 0.8128)
			(drill 0.399796)
			(layers "*.Cu" "*.Mask")
			(remove_unused_layers no)
			(net "P3E_CPU1_PE3_MP_C_TXP<13>")
			(clearance 0.2921)
			(thermal_gap 0.2921)
		)
		(pad "H8" thru_hole circle
			(at 6.999986 -3.50012 270)
			(size 0.8128 0.8128)
			(drill 0.399796)
			(layers "*.Cu" "*.Mask")
			(remove_unused_layers no)
			(net "P3E_CPU1_PE3_MP_C_TXP<10>")
			(clearance 0.2921)
			(thermal_gap 0.2921)
		)
		(pad "I1" thru_hole circle
			(at -6.999986 -4.99999 270)
			(size 0.8636 0.8636)
			(drill 0.499872)
			(layers "*.Cu" "*.Mask")
			(remove_unused_layers no)
			(net "GND")
			(clearance 0.1778)
			(thermal_gap 0.1778)
		)
		(pad "I2" thru_hole circle
			(at -4.99999 -4.899914 270)
			(size 0.8128 0.8128)
			(drill 0.399796)
			(layers "*.Cu" "*.Mask")
			(remove_unused_layers no)
			(net "P3E_CPU1_PE3_MP_RXN<13>")
			(clearance 0.2921)
			(thermal_gap 0.2921)
		)
		(pad "I3" thru_hole circle
			(at -2.999994 -4.99999 270)
			(size 0.8636 0.8636)
			(drill 0.499872)
			(layers "*.Cu" "*.Mask")
			(remove_unused_layers no)
			(net "GND")
			(clearance 0.1778)
			(thermal_gap 0.1778)
		)
		(pad "I4" thru_hole circle
			(at -0.999998 -4.899914 270)
			(size 0.8128 0.8128)
			(drill 0.399796)
			(layers "*.Cu" "*.Mask")
			(remove_unused_layers no)
			(net "TP_IOI4")
			(clearance 0.2921)
			(thermal_gap 0.2921)
		)
		(pad "I5" thru_hole circle
			(at 0.999998 -4.99999 270)
			(size 0.8636 0.8636)
			(drill 0.499872)
			(layers "*.Cu" "*.Mask")
			(remove_unused_layers no)
			(net "GND")
			(clearance 0.1778)
			(thermal_gap 0.1778)
		)
		(pad "I6" thru_hole circle
			(at 2.999994 -4.899914 270)
			(size 0.8128 0.8128)
			(drill 0.399796)
			(layers "*.Cu" "*.Mask")
			(remove_unused_layers no)
			(net "P3E_CPU1_PE3_MP_C_TXP<15>")
			(clearance 0.2921)
			(thermal_gap 0.2921)
		)
		(pad "I7" thru_hole circle
			(at 4.99999 -4.99999 270)
			(size 0.8636 0.8636)
			(drill 0.499872)
			(layers "*.Cu" "*.Mask")
			(remove_unused_layers no)
			(net "GND")
			(clearance 0.1778)
			(thermal_gap 0.1778)
		)
		(pad "I8" thru_hole circle
			(at 6.999986 -4.899914 270)
			(size 0.8128 0.8128)
			(drill 0.399796)
			(layers "*.Cu" "*.Mask")
			(remove_unused_layers no)
			(net "P3E_CPU1_PE3_MP_C_TXN<10>")
			(clearance 0.2921)
			(thermal_gap 0.2921)
		)
		(pad "J2" thru_hole circle
			(at -4.99999 -6.299962 270)
			(size 0.8636 0.8636)
			(drill 0.499872)
			(layers "*.Cu" "*.Mask")
			(remove_unused_layers no)
			(net "GND")
			(clearance 0.1778)
			(thermal_gap 0.1778)
		)
		(pad "J4" thru_hole circle
			(at -0.999998 -6.299962 270)
			(size 0.8636 0.8636)
			(drill 0.499872)
			(layers "*.Cu" "*.Mask")
			(remove_unused_layers no)
			(net "GND")
			(clearance 0.1778)
			(thermal_gap 0.1778)
		)
		(pad "J6" thru_hole circle
			(at 2.999994 -6.299962 270)
			(size 0.8636 0.8636)
			(drill 0.499872)
			(layers "*.Cu" "*.Mask")
			(remove_unused_layers no)
			(net "GND")
			(clearance 0.1778)
			(thermal_gap 0.1778)
		)
		(pad "J8" thru_hole circle
			(at 6.999986 -6.299962 270)
			(size 0.8636 0.8636)
			(drill 0.499872)
			(layers "*.Cu" "*.Mask")
			(remove_unused_layers no)
			(net "GND")
			(clearance 0.1778)
			(thermal_gap 0.1778)
		)
	)
)
